(kicad_pcb
	(version 20260206)
	(generator "pcbnew")
	(generator_version "10.0")
	(general
		(thickness 1.6)
		(legacy_teardrops no)
	)
	(paper "A4")
	(title_block
		(title "12092022_DA0F0TFB6D0_F0T_FAN_BOARD_MP5048_D_brd_v02_OCP.brd")
		(comment 1 "Grand Teton / footprints 404-409 of 924")
	)
	(layers
		(0 "F.Cu" signal "TOP")
		(4 "In1.Cu" signal "GND")
		(6 "In2.Cu" signal "IN1")
		(8 "In3.Cu" signal "IN2")
		(10 "In4.Cu" signal "GND1")
		(2 "B.Cu" signal "BOTTOM")
		(9 "F.Adhes" user "F.Adhesive")
		(11 "B.Adhes" user "B.Adhesive")
		(13 "F.Paste" user "Package Geometry/Pastemask Top")
		(15 "B.Paste" user "Package Geometry/Pastemask Bottom")
		(5 "F.SilkS" user "Ref Des/Silkscreen Top")
		(7 "B.SilkS" user "Ref Des/Silkscreen Bottom")
		(1 "F.Mask" user "Board Geometry/Soldermask Top")
		(3 "B.Mask" user "Board Geometry/Soldermask Bottom")
		(17 "Dwgs.User" user "User.Drawings")
		(19 "Cmts.User" user "User.Comments")
		(21 "Eco1.User" user "User.Eco1")
		(23 "Eco2.User" user "User.Eco2")
		(25 "Edge.Cuts" user "Board Geometry/Outline")
		(27 "Margin" user)
		(31 "F.CrtYd" user "Package Geometry/Place Bound Top")
		(29 "B.CrtYd" user "Package Geometry/Place Bound Bottom")
		(35 "F.Fab" user "Ref Des/Assembly Top")
		(33 "B.Fab" user "Ref Des/Assembly Bottom")
	)
	(footprint ""
		(layer "F.Cu")
		(at 18.923 -197.612 180)
		(property "Reference" "R5316"
			(at 0 0 180)
			(layer "F.SilkS")
			(hide yes)
			(effects
				(font
					(size 1.27 1.27)
				)
			)
		)
		(property "Value" ""
			(at 0 0 180)
			(layer "F.Fab")
			(effects
				(font
					(size 1.27 1.27)
				)
			)
		)
		(duplicate_pad_numbers_are_jumpers no)
		(fp_line
			(start 1.2954 0.5842)
			(end -1.2954 0.5842)
			(stroke
				(width 0.1524)
				(type default)
			)
			(layer "F.SilkS")
		)
		(fp_line
			(start 1.2954 -0.5842)
			(end 1.2954 0.5842)
			(stroke
				(width 0.1524)
				(type default)
			)
			(layer "F.SilkS")
		)
		(fp_line
			(start -1.2954 0.5842)
			(end -1.2954 -0.5842)
			(stroke
				(width 0.1524)
				(type default)
			)
			(layer "F.SilkS")
		)
		(fp_line
			(start -1.2954 -0.5842)
			(end 1.2954 -0.5842)
			(stroke
				(width 0.1524)
				(type default)
			)
			(layer "F.SilkS")
		)
		(fp_line
			(start 1.1938 0.4064)
			(end 0.8636 0.4064)
			(stroke
				(width 0.1)
				(type default)
			)
			(layer "F.Fab")
		)
		(fp_line
			(start 1.1938 -0.406654)
			(end 1.1938 0.4064)
			(stroke
				(width 0.1)
				(type default)
			)
			(layer "F.Fab")
		)
		(fp_line
			(start 0.8636 0.4572)
			(end -0.8636 0.4572)
			(stroke
				(width 0.1)
				(type default)
			)
			(layer "F.Fab")
		)
		(fp_line
			(start 0.8636 0.4064)
			(end 0.8636 0.4572)
			(stroke
				(width 0.1)
				(type default)
			)
			(layer "F.Fab")
		)
		(fp_line
			(start 0.8636 -0.406654)
			(end 1.1938 -0.406654)
			(stroke
				(width 0.1)
				(type default)
			)
			(layer "F.Fab")
		)
		(fp_line
			(start 0.8636 -0.4572)
			(end 0.8636 -0.406654)
			(stroke
				(width 0.1)
				(type default)
			)
			(layer "F.Fab")
		)
		(fp_line
			(start -0.8636 0.4572)
			(end -0.8636 0.4318)
			(stroke
				(width 0.1)
				(type default)
			)
			(layer "F.Fab")
		)
		(fp_line
			(start -0.8636 0.4318)
			(end -0.8636 0.4064)
			(stroke
				(width 0.1)
				(type default)
			)
			(layer "F.Fab")
		)
		(fp_line
			(start -0.8636 0.4064)
			(end -1.1938 0.4064)
			(stroke
				(width 0.1)
				(type default)
			)
			(layer "F.Fab")
		)
		(fp_line
			(start -0.8636 -0.406654)
			(end -0.8636 -0.4572)
			(stroke
				(width 0.1)
				(type default)
			)
			(layer "F.Fab")
		)
		(fp_line
			(start -0.8636 -0.4572)
			(end 0.8636 -0.4572)
			(stroke
				(width 0.1)
				(type default)
			)
			(layer "F.Fab")
		)
		(fp_line
			(start -1.1938 0.4064)
			(end -1.1938 -0.406654)
			(stroke
				(width 0.1)
				(type default)
			)
			(layer "F.Fab")
		)
		(fp_line
			(start -1.1938 -0.406654)
			(end -0.8636 -0.406654)
			(stroke
				(width 0.1)
				(type default)
			)
			(layer "F.Fab")
		)
		(pad "1" smd rect
			(at -0.7366 0 90)
			(size 0.7112 0.8128)
			(layers "F.Cu" "F.Mask" "F.Paste")
			(net "P52V_FAN_6")
		)
		(pad "2" smd rect
			(at 0.7366 0 90)
			(size 0.7112 0.8128)
			(layers "F.Cu" "F.Mask" "F.Paste")
			(net "FAN_6_TACH_IL_R")
		)
	)
	(footprint ""
		(layer "F.Cu")
		(at 25.527 -129.413)
		(property "Reference" "R4944"
			(at 0 0 0)
			(layer "F.SilkS")
			(hide yes)
			(effects
				(font
					(size 1.27 1.27)
				)
			)
		)
		(property "Value" ""
			(at 0 0 0)
			(layer "F.Fab")
			(effects
				(font
					(size 1.27 1.27)
				)
			)
		)
		(duplicate_pad_numbers_are_jumpers no)
		(fp_line
			(start -0.7874 -0.4064)
			(end 0.7874 -0.4064)
			(stroke
				(width 0.1524)
				(type default)
			)
			(layer "F.SilkS")
		)
		(fp_line
			(start -0.7874 0.4064)
			(end -0.7874 -0.4064)
			(stroke
				(width 0.1524)
				(type default)
			)
			(layer "F.SilkS")
		)
		(fp_line
			(start 0.7874 -0.4064)
			(end 0.7874 0.4064)
			(stroke
				(width 0.1524)
				(type default)
			)
			(layer "F.SilkS")
		)
		(fp_line
			(start 0.7874 0.4064)
			(end -0.7874 0.4064)
			(stroke
				(width 0.1524)
				(type default)
			)
			(layer "F.SilkS")
		)
		(fp_line
			(start -0.67945 -0.305054)
			(end -0.12065 -0.305054)
			(stroke
				(width 0.1)
				(type default)
			)
			(layer "F.Fab")
		)
		(fp_line
			(start -0.67945 0.3048)
			(end -0.67945 -0.305054)
			(stroke
				(width 0.1)
				(type default)
			)
			(layer "F.Fab")
		)
		(fp_line
			(start -0.12065 -0.305054)
			(end -0.12065 -0.2794)
			(stroke
				(width 0.1)
				(type default)
			)
			(layer "F.Fab")
		)
		(fp_line
			(start -0.12065 -0.2794)
			(end 0.12065 -0.2794)
			(stroke
				(width 0.1)
				(type default)
			)
			(layer "F.Fab")
		)
		(fp_line
			(start -0.12065 0.2794)
			(end -0.12065 0.3048)
			(stroke
				(width 0.1)
				(type default)
			)
			(layer "F.Fab")
		)
		(fp_line
			(start -0.12065 0.3048)
			(end -0.67945 0.3048)
			(stroke
				(width 0.1)
				(type default)
			)
			(layer "F.Fab")
		)
		(fp_line
			(start 0.120396 0.2794)
			(end -0.12065 0.2794)
			(stroke
				(width 0.1)
				(type default)
			)
			(layer "F.Fab")
		)
		(fp_line
			(start 0.120396 0.3048)
			(end 0.120396 0.2794)
			(stroke
				(width 0.1)
				(type default)
			)
			(layer "F.Fab")
		)
		(fp_line
			(start 0.12065 -0.3048)
			(end 0.67945 -0.3048)
			(stroke
				(width 0.1)
				(type default)
			)
			(layer "F.Fab")
		)
		(fp_line
			(start 0.12065 -0.2794)
			(end 0.12065 -0.3048)
			(stroke
				(width 0.1)
				(type default)
			)
			(layer "F.Fab")
		)
		(fp_line
			(start 0.67945 -0.3048)
			(end 0.67945 0.3048)
			(stroke
				(width 0.1)
				(type default)
			)
			(layer "F.Fab")
		)
		(fp_line
			(start 0.67945 0.3048)
			(end 0.120396 0.3048)
			(stroke
				(width 0.1)
				(type default)
			)
			(layer "F.Fab")
		)
		(pad "1" smd circle
			(at -0.40005 0)
			(size 0 0)
			(layers "F.Cu" "F.Mask" "F.Paste")
			(net "GND")
		)
		(pad "2" smd circle
			(at 0.40005 0)
			(size 0 0)
			(layers "F.Cu" "F.Mask" "F.Paste")
			(net "MAX31790_U317_PWM_START1")
		)
	)
	(footprint ""
		(layer "F.Cu")
		(at 4.826 -97.409)
		(property "Reference" "Q14"
			(at -0.01016 -2.36093 0)
			(unlocked yes)
			(layer "F.SilkS")
			(effects
				(font
					(size 0.7874 0.5842)
					(thickness 0.1524)
				)
				(justify left)
			)
		)
		(property "Value" ""
			(at 0 0 0)
			(layer "F.Fab")
			(effects
				(font
					(size 1.27 1.27)
				)
			)
		)
		(duplicate_pad_numbers_are_jumpers no)
		(fp_line
			(start -1.905 -1.651)
			(end 1.905 -1.651)
			(stroke
				(width 0.1524)
				(type default)
			)
			(layer "F.SilkS")
		)
		(fp_line
			(start -1.905 1.651)
			(end -1.905 -1.651)
			(stroke
				(width 0.1524)
				(type default)
			)
			(layer "F.SilkS")
		)
		(fp_line
			(start 1.905 -1.651)
			(end 1.905 1.651)
			(stroke
				(width 0.1524)
				(type default)
			)
			(layer "F.SilkS")
		)
		(fp_line
			(start 1.905 1.651)
			(end -1.905 1.651)
			(stroke
				(width 0.1524)
				(type default)
			)
			(layer "F.SilkS")
		)
		(fp_line
			(start -1.249934 -1.169924)
			(end -0.6985 -1.169924)
			(stroke
				(width 0.1)
				(type default)
			)
			(layer "F.Fab")
		)
		(fp_line
			(start -1.249934 -0.729996)
			(end -1.249934 -1.169924)
			(stroke
				(width 0.1)
				(type default)
			)
			(layer "F.Fab")
		)
		(fp_line
			(start -1.249934 0.729996)
			(end -0.6985 0.729996)
			(stroke
				(width 0.1)
				(type default)
			)
			(layer "F.Fab")
		)
		(fp_line
			(start -1.249934 1.169924)
			(end -1.249934 0.729996)
			(stroke
				(width 0.1)
				(type default)
			)
			(layer "F.Fab")
		)
		(fp_line
			(start -0.6985 -1.524)
			(end 0.6985 -1.524)
			(stroke
				(width 0.1)
				(type default)
			)
			(layer "F.Fab")
		)
		(fp_line
			(start -0.6985 -1.169924)
			(end -0.6985 -1.524)
			(stroke
				(width 0.1)
				(type default)
			)
			(layer "F.Fab")
		)
		(fp_line
			(start -0.6985 -0.729996)
			(end -1.249934 -0.729996)
			(stroke
				(width 0.1)
				(type default)
			)
			(layer "F.Fab")
		)
		(fp_line
			(start -0.6985 0.729996)
			(end -0.6985 -0.729996)
			(stroke
				(width 0.1)
				(type default)
			)
			(layer "F.Fab")
		)
		(fp_line
			(start -0.6985 1.169924)
			(end -1.249934 1.169924)
			(stroke
				(width 0.1)
				(type default)
			)
			(layer "F.Fab")
		)
		(fp_line
			(start -0.6985 1.524)
			(end -0.6985 1.169924)
			(stroke
				(width 0.1)
				(type default)
			)
			(layer "F.Fab")
		)
		(fp_line
			(start 0.6985 -1.524)
			(end 0.6985 -0.219964)
			(stroke
				(width 0.1)
				(type default)
			)
			(layer "F.Fab")
		)
		(fp_line
			(start 0.6985 -0.219964)
			(end 1.249934 -0.219964)
			(stroke
				(width 0.1)
				(type default)
			)
			(layer "F.Fab")
		)
		(fp_line
			(start 0.6985 0.219964)
			(end 0.6985 1.524)
			(stroke
				(width 0.1)
				(type default)
			)
			(layer "F.Fab")
		)
		(fp_line
			(start 0.6985 1.524)
			(end -0.6985 1.524)
			(stroke
				(width 0.1)
				(type default)
			)
			(layer "F.Fab")
		)
		(fp_line
			(start 1.249934 -0.219964)
			(end 1.249934 0.219964)
			(stroke
				(width 0.1)
				(type default)
			)
			(layer "F.Fab")
		)
		(fp_line
			(start 1.249934 0.219964)
			(end 0.6985 0.219964)
			(stroke
				(width 0.1)
				(type default)
			)
			(layer "F.Fab")
		)
		(fp_rect
			(start -0.6985 1.524)
			(end 0.6985 -1.524)
			(stroke
				(width 0)
				(type default)
			)
			(fill no)
			(layer "F.Fab")
		)
		(pad "D" smd rect
			(at 1.1176 0 270)
			(size 1.016 1.27)
			(layers "F.Cu" "F.Mask" "F.Paste")
			(net "P12V_LED_FAN5")
		)
		(pad "G" smd rect
			(at -1.1176 -1.016 270)
			(size 1.016 1.27)
			(layers "F.Cu" "F.Mask" "F.Paste")
			(net "U410_D1")
		)
		(pad "S" smd rect
			(at -1.1176 1.016 270)
			(size 1.016 1.27)
			(layers "F.Cu" "F.Mask" "F.Paste")
			(net "P12V_LED")
		)
	)
	(footprint ""
		(layer "F.Cu")
		(at 18.415 -187.579)
		(property "Reference" "R314"
			(at 0 0 0)
			(layer "F.SilkS")
			(hide yes)
			(effects
				(font
					(size 1.27 1.27)
				)
			)
		)
		(property "Value" ""
			(at 0 0 0)
			(layer "F.Fab")
			(effects
				(font
					(size 1.27 1.27)
				)
			)
		)
		(duplicate_pad_numbers_are_jumpers no)
		(fp_line
			(start -0.7874 -0.4064)
			(end 0.7874 -0.4064)
			(stroke
				(width 0.1524)
				(type default)
			)
			(layer "F.SilkS")
		)
		(fp_line
			(start -0.7874 0.4064)
			(end -0.7874 -0.4064)
			(stroke
				(width 0.1524)
				(type default)
			)
			(layer "F.SilkS")
		)
		(fp_line
			(start 0.7874 -0.4064)
			(end 0.7874 0.4064)
			(stroke
				(width 0.1524)
				(type default)
			)
			(layer "F.SilkS")
		)
		(fp_line
			(start 0.7874 0.4064)
			(end -0.7874 0.4064)
			(stroke
				(width 0.1524)
				(type default)
			)
			(layer "F.SilkS")
		)
		(fp_line
			(start -0.67945 -0.305054)
			(end -0.12065 -0.305054)
			(stroke
				(width 0.1)
				(type default)
			)
			(layer "F.Fab")
		)
		(fp_line
			(start -0.67945 0.3048)
			(end -0.67945 -0.305054)
			(stroke
				(width 0.1)
				(type default)
			)
			(layer "F.Fab")
		)
		(fp_line
			(start -0.12065 -0.305054)
			(end -0.12065 -0.2794)
			(stroke
				(width 0.1)
				(type default)
			)
			(layer "F.Fab")
		)
		(fp_line
			(start -0.12065 -0.2794)
			(end 0.12065 -0.2794)
			(stroke
				(width 0.1)
				(type default)
			)
			(layer "F.Fab")
		)
		(fp_line
			(start -0.12065 0.2794)
			(end -0.12065 0.3048)
			(stroke
				(width 0.1)
				(type default)
			)
			(layer "F.Fab")
		)
		(fp_line
			(start -0.12065 0.3048)
			(end -0.67945 0.3048)
			(stroke
				(width 0.1)
				(type default)
			)
			(layer "F.Fab")
		)
		(fp_line
			(start 0.120396 0.2794)
			(end -0.12065 0.2794)
			(stroke
				(width 0.1)
				(type default)
			)
			(layer "F.Fab")
		)
		(fp_line
			(start 0.120396 0.3048)
			(end 0.120396 0.2794)
			(stroke
				(width 0.1)
				(type default)
			)
			(layer "F.Fab")
		)
		(fp_line
			(start 0.12065 -0.3048)
			(end 0.67945 -0.3048)
			(stroke
				(width 0.1)
				(type default)
			)
			(layer "F.Fab")
		)
		(fp_line
			(start 0.12065 -0.2794)
			(end 0.12065 -0.3048)
			(stroke
				(width 0.1)
				(type default)
			)
			(layer "F.Fab")
		)
		(fp_line
			(start 0.67945 -0.3048)
			(end 0.67945 0.3048)
			(stroke
				(width 0.1)
				(type default)
			)
			(layer "F.Fab")
		)
		(fp_line
			(start 0.67945 0.3048)
			(end 0.120396 0.3048)
			(stroke
				(width 0.1)
				(type default)
			)
			(layer "F.Fab")
		)
		(pad "1" smd circle
			(at -0.40005 0)
			(size 0 0)
			(layers "F.Cu" "F.Mask" "F.Paste")
			(net "SMB_FRU_CLK")
		)
		(pad "2" smd circle
			(at 0.40005 0)
			(size 0 0)
			(layers "F.Cu" "F.Mask" "F.Paste")
			(net "SMB_PDBV_FAN_SCL")
		)
	)
	(footprint ""
		(layer "F.Cu")
		(at 34.417 -141.351 -90)
		(property "Reference" "R5282"
			(at 0 0 270)
			(layer "F.SilkS")
			(hide yes)
			(effects
				(font
					(size 1.27 1.27)
				)
			)
		)
		(property "Value" ""
			(at 0 0 270)
			(layer "F.Fab")
			(effects
				(font
					(size 1.27 1.27)
				)
			)
		)
		(duplicate_pad_numbers_are_jumpers no)
		(fp_line
			(start -0.7874 0.4064)
			(end -0.7874 -0.4064)
			(stroke
				(width 0.1524)
				(type default)
			)
			(layer "F.SilkS")
		)
		(fp_line
			(start 0.7874 0.4064)
			(end -0.7874 0.4064)
			(stroke
				(width 0.1524)
				(type default)
			)
			(layer "F.SilkS")
		)
		(fp_line
			(start -0.7874 -0.4064)
			(end 0.7874 -0.4064)
			(stroke
				(width 0.1524)
				(type default)
			)
			(layer "F.SilkS")
		)
		(fp_line
			(start 0.7874 -0.4064)
			(end 0.7874 0.4064)
			(stroke
				(width 0.1524)
				(type default)
			)
			(layer "F.SilkS")
		)
		(fp_line
			(start -0.67945 0.3048)
			(end -0.67945 -0.305054)
			(stroke
				(width 0.1)
				(type default)
			)
			(layer "F.Fab")
		)
		(fp_line
			(start -0.12065 0.3048)
			(end -0.67945 0.3048)
			(stroke
				(width 0.1)
				(type default)
			)
			(layer "F.Fab")
		)
		(fp_line
			(start 0.120396 0.3048)
			(end 0.120396 0.2794)
			(stroke
				(width 0.1)
				(type default)
			)
			(layer "F.Fab")
		)
		(fp_line
			(start 0.67945 0.3048)
			(end 0.120396 0.3048)
			(stroke
				(width 0.1)
				(type default)
			)
			(layer "F.Fab")
		)
		(fp_line
			(start -0.12065 0.2794)
			(end -0.12065 0.3048)
			(stroke
				(width 0.1)
				(type default)
			)
			(layer "F.Fab")
		)
		(fp_line
			(start 0.120396 0.2794)
			(end -0.12065 0.2794)
			(stroke
				(width 0.1)
				(type default)
			)
			(layer "F.Fab")
		)
		(fp_line
			(start -0.12065 -0.2794)
			(end 0.12065 -0.2794)
			(stroke
				(width 0.1)
				(type default)
			)
			(layer "F.Fab")
		)
		(fp_line
			(start 0.12065 -0.2794)
			(end 0.12065 -0.3048)
			(stroke
				(width 0.1)
				(type default)
			)
			(layer "F.Fab")
		)
		(fp_line
			(start 0.12065 -0.3048)
			(end 0.67945 -0.3048)
			(stroke
				(width 0.1)
				(type default)
			)
			(layer "F.Fab")
		)
		(fp_line
			(start 0.67945 -0.3048)
			(end 0.67945 0.3048)
			(stroke
				(width 0.1)
				(type default)
			)
			(layer "F.Fab")
		)
		(fp_line
			(start -0.67945 -0.305054)
			(end -0.12065 -0.305054)
			(stroke
				(width 0.1)
				(type default)
			)
			(layer "F.Fab")
		)
		(fp_line
			(start -0.12065 -0.305054)
			(end -0.12065 -0.2794)
			(stroke
				(width 0.1)
				(type default)
			)
			(layer "F.Fab")
		)
		(pad "1" smd circle
			(at -0.40005 0 270)
			(size 0 0)
			(layers "F.Cu" "F.Mask" "F.Paste")
			(net "SMB_FAN3_R_SCL")
		)
		(pad "2" smd circle
			(at 0.40005 0 270)
			(size 0 0)
			(layers "F.Cu" "F.Mask" "F.Paste")
			(net "P3V3_AUX")
		)
	)
	(footprint ""
		(layer "F.Cu")
		(at 45.085 -179.324)
		(property "Reference" "R5490"
			(at 0 0 0)
			(layer "F.SilkS")
			(hide yes)
			(effects
				(font
					(size 1.27 1.27)
				)
			)
		)
		(property "Value" ""
			(at 0 0 0)
			(layer "F.Fab")
			(effects
				(font
					(size 1.27 1.27)
				)
			)
		)
		(duplicate_pad_numbers_are_jumpers no)
		(fp_line
			(start -0.7874 -0.4064)
			(end 0.7874 -0.4064)
			(stroke
				(width 0.1524)
				(type default)
			)
			(layer "F.SilkS")
		)
		(fp_line
			(start -0.7874 0.4064)
			(end -0.7874 -0.4064)
			(stroke
				(width 0.1524)
				(type default)
			)
			(layer "F.SilkS")
		)
		(fp_line
			(start 0.7874 -0.4064)
			(end 0.7874 0.4064)
			(stroke
				(width 0.1524)
				(type default)
			)
			(layer "F.SilkS")
		)
		(fp_line
			(start 0.7874 0.4064)
			(end -0.7874 0.4064)
			(stroke
				(width 0.1524)
				(type default)
			)
			(layer "F.SilkS")
		)
		(fp_line
			(start -0.67945 -0.305054)
			(end -0.12065 -0.305054)
			(stroke
				(width 0.1)
				(type default)
			)
			(layer "F.Fab")
		)
		(fp_line
			(start -0.67945 0.3048)
			(end -0.67945 -0.305054)
			(stroke
				(width 0.1)
				(type default)
			)
			(layer "F.Fab")
		)
		(fp_line
			(start -0.12065 -0.305054)
			(end -0.12065 -0.2794)
			(stroke
				(width 0.1)
				(type default)
			)
			(layer "F.Fab")
		)
		(fp_line
			(start -0.12065 -0.2794)
			(end 0.12065 -0.2794)
			(stroke
				(width 0.1)
				(type default)
			)
			(layer "F.Fab")
		)
		(fp_line
			(start -0.12065 0.2794)
			(end -0.12065 0.3048)
			(stroke
				(width 0.1)
				(type default)
			)
			(layer "F.Fab")
		)
		(fp_line
			(start -0.12065 0.3048)
			(end -0.67945 0.3048)
			(stroke
				(width 0.1)
				(type default)
			)
			(layer "F.Fab")
		)
		(fp_line
			(start 0.120396 0.2794)
			(end -0.12065 0.2794)
			(stroke
				(width 0.1)
				(type default)
			)
			(layer "F.Fab")
		)
		(fp_line
			(start 0.120396 0.3048)
			(end 0.120396 0.2794)
			(stroke
				(width 0.1)
				(type default)
			)
			(layer "F.Fab")
		)
		(fp_line
			(start 0.12065 -0.3048)
			(end 0.67945 -0.3048)
			(stroke
				(width 0.1)
				(type default)
			)
			(layer "F.Fab")
		)
		(fp_line
			(start 0.12065 -0.2794)
			(end 0.12065 -0.3048)
			(stroke
				(width 0.1)
				(type default)
			)
			(layer "F.Fab")
		)
		(fp_line
			(start 0.67945 -0.3048)
			(end 0.67945 0.3048)
			(stroke
				(width 0.1)
				(type default)
			)
			(layer "F.Fab")
		)
		(fp_line
			(start 0.67945 0.3048)
			(end 0.120396 0.3048)
			(stroke
				(width 0.1)
				(type default)
			)
			(layer "F.Fab")
		)
		(pad "1" smd circle
			(at -0.40005 0)
			(size 0 0)
			(layers "F.Cu" "F.Mask" "F.Paste")
			(net "P52V_FAN_3_BUFF_EN")
		)
		(pad "2" smd circle
			(at 0.40005 0)
			(size 0 0)
			(layers "F.Cu" "F.Mask" "F.Paste")
			(net "P52V_FAN_3_BUFF_EN_R")
		)
	)
)
